(kicad_pcb
	(version 20260206)
	(generator "pcbnew")
	(generator_version "10.0")
	(general
		(thickness 1.6)
		(legacy_teardrops no)
	)
	(paper "A4")
	(title_block
		(title "01162023_DA0F0TEBIF0_F0T_Expander_BD_F_brd_V02_OCP.brd")
		(comment 1 "Grand Teton / footprints 2683-2689 of 9728")
	)
	(layers
		(0 "F.Cu" signal "TOP")
		(4 "In1.Cu" signal "GND")
		(6 "In2.Cu" signal "VCC")
		(8 "In3.Cu" signal "VCC1")
		(10 "In4.Cu" signal "GND1")
		(12 "In5.Cu" signal "IN1")
		(14 "In6.Cu" signal "GND2")
		(16 "In7.Cu" signal "IN2")
		(18 "In8.Cu" signal "GND3")
		(20 "In9.Cu" signal "IN3")
		(22 "In10.Cu" signal "GND4")
		(24 "In11.Cu" signal "IN4")
		(26 "In12.Cu" signal "GND5")
		(28 "In13.Cu" signal "IN5")
		(30 "In14.Cu" signal "GND6")
		(32 "In15.Cu" signal "IN6")
		(34 "In16.Cu" signal "GND7")
		(2 "B.Cu" signal "BOTTOM")
		(9 "F.Adhes" user "F.Adhesive")
		(11 "B.Adhes" user "B.Adhesive")
		(13 "F.Paste" user "Package Geometry/Pastemask Top")
		(15 "B.Paste" user "Package Geometry/Pastemask Bottom")
		(5 "F.SilkS" user "Ref Des/Silkscreen Top")
		(7 "B.SilkS" user "Ref Des/Silkscreen Bottom")
		(1 "F.Mask" user "Board Geometry/Soldermask Top")
		(3 "B.Mask" user "Board Geometry/Soldermask Bottom")
		(17 "Dwgs.User" user "User.Drawings")
		(19 "Cmts.User" user "User.Comments")
		(21 "Eco1.User" user "User.Eco1")
		(23 "Eco2.User" user "User.Eco2")
		(25 "Edge.Cuts" user "Board Geometry/Outline")
		(27 "Margin" user)
		(31 "F.CrtYd" user "Package Geometry/Place Bound Top")
		(29 "B.CrtYd" user "Package Geometry/Place Bound Bottom")
		(35 "F.Fab" user "Ref Des/Assembly Top")
		(33 "B.Fab" user "Ref Des/Assembly Bottom")
	)
	(footprint ""
		(layer "F.Cu")
		(at 338.074 -173.101 180)
		(property "Reference" "R4781"
			(at 0 0 180)
			(layer "F.SilkS")
			(hide yes)
			(effects
				(font
					(size 1.27 1.27)
				)
			)
		)
		(property "Value" ""
			(at 0 0 180)
			(layer "F.Fab")
			(effects
				(font
					(size 1.27 1.27)
				)
			)
		)
		(duplicate_pad_numbers_are_jumpers no)
		(fp_line
			(start 0.7874 0.4064)
			(end -0.7874 0.4064)
			(stroke
				(width 0.1524)
				(type default)
			)
			(layer "F.SilkS")
		)
		(fp_line
			(start 0.7874 -0.4064)
			(end 0.7874 0.4064)
			(stroke
				(width 0.1524)
				(type default)
			)
			(layer "F.SilkS")
		)
		(fp_line
			(start -0.7874 0.4064)
			(end -0.7874 -0.4064)
			(stroke
				(width 0.1524)
				(type default)
			)
			(layer "F.SilkS")
		)
		(fp_line
			(start -0.7874 -0.4064)
			(end 0.7874 -0.4064)
			(stroke
				(width 0.1524)
				(type default)
			)
			(layer "F.SilkS")
		)
		(fp_line
			(start 0.67945 0.3048)
			(end 0.120396 0.3048)
			(stroke
				(width 0.1)
				(type default)
			)
			(layer "F.Fab")
		)
		(fp_line
			(start 0.67945 -0.3048)
			(end 0.67945 0.3048)
			(stroke
				(width 0.1)
				(type default)
			)
			(layer "F.Fab")
		)
		(fp_line
			(start 0.12065 -0.2794)
			(end 0.12065 -0.3048)
			(stroke
				(width 0.1)
				(type default)
			)
			(layer "F.Fab")
		)
		(fp_line
			(start 0.12065 -0.3048)
			(end 0.67945 -0.3048)
			(stroke
				(width 0.1)
				(type default)
			)
			(layer "F.Fab")
		)
		(fp_line
			(start 0.120396 0.3048)
			(end 0.120396 0.2794)
			(stroke
				(width 0.1)
				(type default)
			)
			(layer "F.Fab")
		)
		(fp_line
			(start 0.120396 0.2794)
			(end -0.12065 0.2794)
			(stroke
				(width 0.1)
				(type default)
			)
			(layer "F.Fab")
		)
		(fp_line
			(start -0.12065 0.3048)
			(end -0.67945 0.3048)
			(stroke
				(width 0.1)
				(type default)
			)
			(layer "F.Fab")
		)
		(fp_line
			(start -0.12065 0.2794)
			(end -0.12065 0.3048)
			(stroke
				(width 0.1)
				(type default)
			)
			(layer "F.Fab")
		)
		(fp_line
			(start -0.12065 -0.2794)
			(end 0.12065 -0.2794)
			(stroke
				(width 0.1)
				(type default)
			)
			(layer "F.Fab")
		)
		(fp_line
			(start -0.12065 -0.305054)
			(end -0.12065 -0.2794)
			(stroke
				(width 0.1)
				(type default)
			)
			(layer "F.Fab")
		)
		(fp_line
			(start -0.67945 0.3048)
			(end -0.67945 -0.305054)
			(stroke
				(width 0.1)
				(type default)
			)
			(layer "F.Fab")
		)
		(fp_line
			(start -0.67945 -0.305054)
			(end -0.12065 -0.305054)
			(stroke
				(width 0.1)
				(type default)
			)
			(layer "F.Fab")
		)
		(pad "1" smd circle
			(at -0.40005 0 180)
			(size 0 0)
			(layers "F.Cu" "F.Mask" "F.Paste")
			(net "GND")
		)
		(pad "2" smd circle
			(at 0.40005 0 180)
			(size 0 0)
			(layers "F.Cu" "F.Mask" "F.Paste")
			(net "PCA9555_1_PEX2_A1")
		)
	)
	(footprint ""
		(layer "F.Cu")
		(at 147.394168 -35.264852)
		(property "Reference" "R5668"
			(at 0 0 0)
			(layer "F.SilkS")
			(hide yes)
			(effects
				(font
					(size 1.27 1.27)
				)
			)
		)
		(property "Value" ""
			(at 0 0 0)
			(layer "F.Fab")
			(effects
				(font
					(size 1.27 1.27)
				)
			)
		)
		(duplicate_pad_numbers_are_jumpers no)
		(fp_line
			(start -0.7874 -0.4064)
			(end 0.7874 -0.4064)
			(stroke
				(width 0.1524)
				(type default)
			)
			(layer "F.SilkS")
		)
		(fp_line
			(start -0.7874 0.4064)
			(end -0.7874 -0.4064)
			(stroke
				(width 0.1524)
				(type default)
			)
			(layer "F.SilkS")
		)
		(fp_line
			(start 0.7874 -0.4064)
			(end 0.7874 0.4064)
			(stroke
				(width 0.1524)
				(type default)
			)
			(layer "F.SilkS")
		)
		(fp_line
			(start 0.7874 0.4064)
			(end -0.7874 0.4064)
			(stroke
				(width 0.1524)
				(type default)
			)
			(layer "F.SilkS")
		)
		(fp_line
			(start -0.67945 -0.305054)
			(end -0.12065 -0.305054)
			(stroke
				(width 0.1)
				(type default)
			)
			(layer "F.Fab")
		)
		(fp_line
			(start -0.67945 0.3048)
			(end -0.67945 -0.305054)
			(stroke
				(width 0.1)
				(type default)
			)
			(layer "F.Fab")
		)
		(fp_line
			(start -0.12065 -0.305054)
			(end -0.12065 -0.2794)
			(stroke
				(width 0.1)
				(type default)
			)
			(layer "F.Fab")
		)
		(fp_line
			(start -0.12065 -0.2794)
			(end 0.12065 -0.2794)
			(stroke
				(width 0.1)
				(type default)
			)
			(layer "F.Fab")
		)
		(fp_line
			(start -0.12065 0.2794)
			(end -0.12065 0.3048)
			(stroke
				(width 0.1)
				(type default)
			)
			(layer "F.Fab")
		)
		(fp_line
			(start -0.12065 0.3048)
			(end -0.67945 0.3048)
			(stroke
				(width 0.1)
				(type default)
			)
			(layer "F.Fab")
		)
		(fp_line
			(start 0.120396 0.2794)
			(end -0.12065 0.2794)
			(stroke
				(width 0.1)
				(type default)
			)
			(layer "F.Fab")
		)
		(fp_line
			(start 0.120396 0.3048)
			(end 0.120396 0.2794)
			(stroke
				(width 0.1)
				(type default)
			)
			(layer "F.Fab")
		)
		(fp_line
			(start 0.12065 -0.3048)
			(end 0.67945 -0.3048)
			(stroke
				(width 0.1)
				(type default)
			)
			(layer "F.Fab")
		)
		(fp_line
			(start 0.12065 -0.2794)
			(end 0.12065 -0.3048)
			(stroke
				(width 0.1)
				(type default)
			)
			(layer "F.Fab")
		)
		(fp_line
			(start 0.67945 -0.3048)
			(end 0.67945 0.3048)
			(stroke
				(width 0.1)
				(type default)
			)
			(layer "F.Fab")
		)
		(fp_line
			(start 0.67945 0.3048)
			(end 0.120396 0.3048)
			(stroke
				(width 0.1)
				(type default)
			)
			(layer "F.Fab")
		)
		(pad "1" smd circle
			(at -0.40005 0)
			(size 0 0)
			(layers "F.Cu" "F.Mask" "F.Paste")
			(net "RST_SMB_SSD5_ISO_N")
		)
		(pad "2" smd circle
			(at 0.40005 0)
			(size 0 0)
			(layers "F.Cu" "F.Mask" "F.Paste")
			(net "GND")
		)
	)
	(footprint ""
		(layer "F.Cu")
		(at 93.201236 -55.78475 -90)
		(property "Reference" "PD34"
			(at 3.91795 2.115566 90)
			(unlocked yes)
			(layer "F.SilkS")
			(effects
				(font
					(size 0.7874 0.5842)
					(thickness 0.1524)
				)
				(justify left)
			)
		)
		(property "Value" ""
			(at 0 0 270)
			(layer "F.Fab")
			(effects
				(font
					(size 1.27 1.27)
				)
			)
		)
		(duplicate_pad_numbers_are_jumpers no)
		(fp_line
			(start -3.400044 1.459992)
			(end -3.400044 -1.459992)
			(stroke
				(width 0.1524)
				(type default)
			)
			(layer "F.SilkS")
		)
		(fp_line
			(start 4.107942 1.459992)
			(end -3.400044 1.459992)
			(stroke
				(width 0.1524)
				(type default)
			)
			(layer "F.SilkS")
		)
		(fp_line
			(start -3.400044 -1.459992)
			(end 4.107942 -1.459992)
			(stroke
				(width 0.1524)
				(type default)
			)
			(layer "F.SilkS")
		)
		(fp_line
			(start 4.107942 -1.459992)
			(end 4.107942 1.459992)
			(stroke
				(width 0.1524)
				(type default)
			)
			(layer "F.SilkS")
		)
		(fp_poly
			(pts
				(xy 4.107942 -1.459992) (xy 4.107942 1.459992) (xy 3.308096 1.459992) (xy 3.308096 -1.459992)
			)
			(stroke
				(width 0)
				(type default)
			)
			(fill yes)
			(layer "F.SilkS")
		)
		(fp_line
			(start -2.29997 1.459992)
			(end -2.29997 -1.459992)
			(stroke
				(width 0.1)
				(type default)
			)
			(layer "F.Fab")
		)
		(fp_line
			(start 2.29997 1.459992)
			(end -2.29997 1.459992)
			(stroke
				(width 0.1)
				(type default)
			)
			(layer "F.Fab")
		)
		(fp_line
			(start -2.29997 -1.459992)
			(end 2.29997 -1.459992)
			(stroke
				(width 0.1)
				(type default)
			)
			(layer "F.Fab")
		)
		(fp_line
			(start 2.29997 -1.459992)
			(end 2.29997 1.459992)
			(stroke
				(width 0.1)
				(type default)
			)
			(layer "F.Fab")
		)
		(fp_text user "-"
			(at 5.4102 0.29845 90)
			(unlocked yes)
			(layer "F.SilkS")
			(effects
				(font
					(size 1.905 1.4224)
					(thickness 0.1524)
				)
				(justify left)
			)
		)
		(fp_text user "+"
			(at -4.7752 -0.12065 270)
			(unlocked yes)
			(layer "F.SilkS")
			(effects
				(font
					(size 1.905 1.4224)
					(thickness 0.1524)
				)
				(justify left)
			)
		)
		(fp_text user "-"
			(at 5.4102 0.29845 90)
			(unlocked yes)
			(layer "F.Fab")
			(effects
				(font
					(size 1.905 1.4224)
					(thickness 0.1524)
				)
				(justify left)
			)
		)
		(fp_text user "+"
			(at -4.7752 -0.12065 270)
			(unlocked yes)
			(layer "F.Fab")
			(effects
				(font
					(size 1.905 1.4224)
					(thickness 0.1524)
				)
				(justify left)
			)
		)
		(pad "A" smd rect
			(at -1.999996 0)
			(size 1.7018 2.5146)
			(layers "F.Cu" "F.Mask" "F.Paste")
			(net "GND")
		)
		(pad "C" smd rect
			(at 1.999996 0)
			(size 1.7018 2.5146)
			(layers "F.Cu" "F.Mask" "F.Paste")
			(net "P12V_SSD3_R")
		)
	)
	(footprint ""
		(layer "F.Cu")
		(at 387.35381 -229.87635 -90)
		(property "Reference" "R5776"
			(at 0 0 270)
			(layer "F.SilkS")
			(hide yes)
			(effects
				(font
					(size 1.27 1.27)
				)
			)
		)
		(property "Value" ""
			(at 0 0 270)
			(layer "F.Fab")
			(effects
				(font
					(size 1.27 1.27)
				)
			)
		)
		(duplicate_pad_numbers_are_jumpers no)
		(fp_line
			(start -0.7874 0.4064)
			(end -0.7874 -0.4064)
			(stroke
				(width 0.1524)
				(type default)
			)
			(layer "F.SilkS")
		)
		(fp_line
			(start 0.7874 0.4064)
			(end -0.7874 0.4064)
			(stroke
				(width 0.1524)
				(type default)
			)
			(layer "F.SilkS")
		)
		(fp_line
			(start -0.7874 -0.4064)
			(end 0.7874 -0.4064)
			(stroke
				(width 0.1524)
				(type default)
			)
			(layer "F.SilkS")
		)
		(fp_line
			(start 0.7874 -0.4064)
			(end 0.7874 0.4064)
			(stroke
				(width 0.1524)
				(type default)
			)
			(layer "F.SilkS")
		)
		(fp_line
			(start -0.67945 0.3048)
			(end -0.67945 -0.305054)
			(stroke
				(width 0.1)
				(type default)
			)
			(layer "F.Fab")
		)
		(fp_line
			(start -0.12065 0.3048)
			(end -0.67945 0.3048)
			(stroke
				(width 0.1)
				(type default)
			)
			(layer "F.Fab")
		)
		(fp_line
			(start 0.120396 0.3048)
			(end 0.120396 0.2794)
			(stroke
				(width 0.1)
				(type default)
			)
			(layer "F.Fab")
		)
		(fp_line
			(start 0.67945 0.3048)
			(end 0.120396 0.3048)
			(stroke
				(width 0.1)
				(type default)
			)
			(layer "F.Fab")
		)
		(fp_line
			(start -0.12065 0.2794)
			(end -0.12065 0.3048)
			(stroke
				(width 0.1)
				(type default)
			)
			(layer "F.Fab")
		)
		(fp_line
			(start 0.120396 0.2794)
			(end -0.12065 0.2794)
			(stroke
				(width 0.1)
				(type default)
			)
			(layer "F.Fab")
		)
		(fp_line
			(start -0.12065 -0.2794)
			(end 0.12065 -0.2794)
			(stroke
				(width 0.1)
				(type default)
			)
			(layer "F.Fab")
		)
		(fp_line
			(start 0.12065 -0.2794)
			(end 0.12065 -0.3048)
			(stroke
				(width 0.1)
				(type default)
			)
			(layer "F.Fab")
		)
		(fp_line
			(start 0.12065 -0.3048)
			(end 0.67945 -0.3048)
			(stroke
				(width 0.1)
				(type default)
			)
			(layer "F.Fab")
		)
		(fp_line
			(start 0.67945 -0.3048)
			(end 0.67945 0.3048)
			(stroke
				(width 0.1)
				(type default)
			)
			(layer "F.Fab")
		)
		(fp_line
			(start -0.67945 -0.305054)
			(end -0.12065 -0.305054)
			(stroke
				(width 0.1)
				(type default)
			)
			(layer "F.Fab")
		)
		(fp_line
			(start -0.12065 -0.305054)
			(end -0.12065 -0.2794)
			(stroke
				(width 0.1)
				(type default)
			)
			(layer "F.Fab")
		)
		(pad "1" smd circle
			(at -0.40005 0 270)
			(size 0 0)
			(layers "F.Cu" "F.Mask" "F.Paste")
			(net "RST_FT4232_SDB_R_N")
		)
		(pad "2" smd circle
			(at 0.40005 0 270)
			(size 0 0)
			(layers "F.Cu" "F.Mask" "F.Paste")
			(net "RST_FT4232_R_N")
		)
	)
	(footprint ""
		(layer "F.Cu")
		(at 362.580936 -118.378986 90)
		(property "Reference" "PC915"
			(at 0 0 90)
			(layer "F.SilkS")
			(hide yes)
			(effects
				(font
					(size 1.27 1.27)
				)
			)
		)
		(property "Value" ""
			(at 0 0 90)
			(layer "F.Fab")
			(effects
				(font
					(size 1.27 1.27)
				)
			)
		)
		(duplicate_pad_numbers_are_jumpers no)
		(fp_line
			(start 0.7874 -0.4064)
			(end 0.7874 0.4064)
			(stroke
				(width 0.1524)
				(type default)
			)
			(layer "F.SilkS")
		)
		(fp_line
			(start -0.7874 -0.4064)
			(end 0.7874 -0.4064)
			(stroke
				(width 0.1524)
				(type default)
			)
			(layer "F.SilkS")
		)
		(fp_line
			(start 0.7874 0.4064)
			(end -0.7874 0.4064)
			(stroke
				(width 0.1524)
				(type default)
			)
			(layer "F.SilkS")
		)
		(fp_line
			(start -0.7874 0.4064)
			(end -0.7874 -0.4064)
			(stroke
				(width 0.1524)
				(type default)
			)
			(layer "F.SilkS")
		)
		(fp_line
			(start -0.12065 -0.305054)
			(end -0.12065 -0.2794)
			(stroke
				(width 0.1)
				(type default)
			)
			(layer "F.Fab")
		)
		(fp_line
			(start -0.67945 -0.305054)
			(end -0.12065 -0.305054)
			(stroke
				(width 0.1)
				(type default)
			)
			(layer "F.Fab")
		)
		(fp_line
			(start 0.67945 -0.3048)
			(end 0.67945 0.3048)
			(stroke
				(width 0.1)
				(type default)
			)
			(layer "F.Fab")
		)
		(fp_line
			(start 0.12065 -0.3048)
			(end 0.67945 -0.3048)
			(stroke
				(width 0.1)
				(type default)
			)
			(layer "F.Fab")
		)
		(fp_line
			(start 0.12065 -0.2794)
			(end 0.12065 -0.3048)
			(stroke
				(width 0.1)
				(type default)
			)
			(layer "F.Fab")
		)
		(fp_line
			(start -0.12065 -0.2794)
			(end 0.12065 -0.2794)
			(stroke
				(width 0.1)
				(type default)
			)
			(layer "F.Fab")
		)
		(fp_line
			(start 0.120396 0.2794)
			(end -0.12065 0.2794)
			(stroke
				(width 0.1)
				(type default)
			)
			(layer "F.Fab")
		)
		(fp_line
			(start -0.12065 0.2794)
			(end -0.12065 0.3048)
			(stroke
				(width 0.1)
				(type default)
			)
			(layer "F.Fab")
		)
		(fp_line
			(start 0.67945 0.3048)
			(end 0.120396 0.3048)
			(stroke
				(width 0.1)
				(type default)
			)
			(layer "F.Fab")
		)
		(fp_line
			(start 0.120396 0.3048)
			(end 0.120396 0.2794)
			(stroke
				(width 0.1)
				(type default)
			)
			(layer "F.Fab")
		)
		(fp_line
			(start -0.12065 0.3048)
			(end -0.67945 0.3048)
			(stroke
				(width 0.1)
				(type default)
			)
			(layer "F.Fab")
		)
		(fp_line
			(start -0.67945 0.3048)
			(end -0.67945 -0.305054)
			(stroke
				(width 0.1)
				(type default)
			)
			(layer "F.Fab")
		)
		(pad "1" smd circle
			(at -0.40005 0 90)
			(size 0 0)
			(layers "F.Cu" "F.Mask" "F.Paste")
			(net "P3V3_NIC6_CO_DV_DT")
		)
		(pad "2" smd circle
			(at 0.40005 0 90)
			(size 0 0)
			(layers "F.Cu" "F.Mask" "F.Paste")
			(net "GND")
		)
	)
	(footprint ""
		(layer "F.Cu")
		(at 392.9253 -350.098614 90)
		(property "Reference" "C740"
			(at 0 0 90)
			(layer "F.SilkS")
			(hide yes)
			(effects
				(font
					(size 1.27 1.27)
				)
			)
		)
		(property "Value" ""
			(at 0 0 90)
			(layer "F.Fab")
			(effects
				(font
					(size 1.27 1.27)
				)
			)
		)
		(duplicate_pad_numbers_are_jumpers no)
		(fp_line
			(start 0.299974 -0.150114)
			(end 0.299974 0.150114)
			(stroke
				(width 0.1)
				(type default)
			)
			(layer "F.Fab")
		)
		(fp_line
			(start -0.299974 -0.150114)
			(end 0.299974 -0.150114)
			(stroke
				(width 0.1)
				(type default)
			)
			(layer "F.Fab")
		)
		(fp_line
			(start 0.299974 0.150114)
			(end -0.299974 0.150114)
			(stroke
				(width 0.1)
				(type default)
			)
			(layer "F.Fab")
		)
		(fp_line
			(start -0.299974 0.150114)
			(end -0.299974 -0.150114)
			(stroke
				(width 0.1)
				(type default)
			)
			(layer "F.Fab")
		)
		(pad "1" smd rect
			(at -0.2667 0 90)
			(size 0.3048 0.381)
			(layers "F.Cu" "F.Mask" "F.Paste")
			(net "P5E_PEX3_STN5_TX_DP<90>")
		)
		(pad "2" smd rect
			(at 0.2667 0 90)
			(size 0.3048 0.381)
			(layers "F.Cu" "F.Mask" "F.Paste")
			(net "P5E_PEX3_STN5_TX_C_DP<90>")
		)
	)
	(footprint ""
		(layer "F.Cu")
		(at 168.343834 -46.90491)
		(property "Reference" "R565"
			(at 0 0 0)
			(layer "F.SilkS")
			(hide yes)
			(effects
				(font
					(size 1.27 1.27)
				)
			)
		)
		(property "Value" ""
			(at 0 0 0)
			(layer "F.Fab")
			(effects
				(font
					(size 1.27 1.27)
				)
			)
		)
		(duplicate_pad_numbers_are_jumpers no)
		(fp_line
			(start -0.7874 -0.4064)
			(end 0.7874 -0.4064)
			(stroke
				(width 0.1524)
				(type default)
			)
			(layer "F.SilkS")
		)
		(fp_line
			(start -0.7874 0.4064)
			(end -0.7874 -0.4064)
			(stroke
				(width 0.1524)
				(type default)
			)
			(layer "F.SilkS")
		)
		(fp_line
			(start 0.7874 -0.4064)
			(end 0.7874 0.4064)
			(stroke
				(width 0.1524)
				(type default)
			)
			(layer "F.SilkS")
		)
		(fp_line
			(start 0.7874 0.4064)
			(end -0.7874 0.4064)
			(stroke
				(width 0.1524)
				(type default)
			)
			(layer "F.SilkS")
		)
		(fp_line
			(start -0.67945 -0.305054)
			(end -0.12065 -0.305054)
			(stroke
				(width 0.1)
				(type default)
			)
			(layer "F.Fab")
		)
		(fp_line
			(start -0.67945 0.3048)
			(end -0.67945 -0.305054)
			(stroke
				(width 0.1)
				(type default)
			)
			(layer "F.Fab")
		)
		(fp_line
			(start -0.12065 -0.305054)
			(end -0.12065 -0.2794)
			(stroke
				(width 0.1)
				(type default)
			)
			(layer "F.Fab")
		)
		(fp_line
			(start -0.12065 -0.2794)
			(end 0.12065 -0.2794)
			(stroke
				(width 0.1)
				(type default)
			)
			(layer "F.Fab")
		)
		(fp_line
			(start -0.12065 0.2794)
			(end -0.12065 0.3048)
			(stroke
				(width 0.1)
				(type default)
			)
			(layer "F.Fab")
		)
		(fp_line
			(start -0.12065 0.3048)
			(end -0.67945 0.3048)
			(stroke
				(width 0.1)
				(type default)
			)
			(layer "F.Fab")
		)
		(fp_line
			(start 0.120396 0.2794)
			(end -0.12065 0.2794)
			(stroke
				(width 0.1)
				(type default)
			)
			(layer "F.Fab")
		)
		(fp_line
			(start 0.120396 0.3048)
			(end 0.120396 0.2794)
			(stroke
				(width 0.1)
				(type default)
			)
			(layer "F.Fab")
		)
		(fp_line
			(start 0.12065 -0.3048)
			(end 0.67945 -0.3048)
			(stroke
				(width 0.1)
				(type default)
			)
			(layer "F.Fab")
		)
		(fp_line
			(start 0.12065 -0.2794)
			(end 0.12065 -0.3048)
			(stroke
				(width 0.1)
				(type default)
			)
			(layer "F.Fab")
		)
		(fp_line
			(start 0.67945 -0.3048)
			(end 0.67945 0.3048)
			(stroke
				(width 0.1)
				(type default)
			)
			(layer "F.Fab")
		)
		(fp_line
			(start 0.67945 0.3048)
			(end 0.120396 0.3048)
			(stroke
				(width 0.1)
				(type default)
			)
			(layer "F.Fab")
		)
		(pad "1" smd circle
			(at -0.40005 0)
			(size 0 0)
			(layers "F.Cu" "F.Mask" "F.Paste")
			(net "SSD5_ADC_ALERT_N")
		)
		(pad "2" smd circle
			(at 0.40005 0)
			(size 0 0)
			(layers "F.Cu" "F.Mask" "F.Paste")
			(net "SSD_0_7_ADC_ALERT_N")
		)
	)
)
